# T6G (Grand Teton) — schematic netlist excerpt (pin names and nets, part order shuffled) for the footprints in the layout excerpt that follows; sources: Cadence DE-HDL packaged netlist, KiCad conversion of 04192023_DAF0TMB3IC0_F0TG_MB_C_brd_V02_OCP.brd

C2598  Q_CAP  22UF 4V 20% X6S  pkg C0402  page 70 : A = PVDDIO_P0 ; B = GND
R742  Q_RES  10K 5% EMPTY  pkg 0402LF  page 76 : A = PVDD18_S5_P0 ; B = PD_ESPI_CPU0_CLK2
R1042  Q_RES  0 5% CHIP  pkg 0201LF  page 288 : A = NCF_CPU0_P1_GND ; B = GND

(kicad_pcb
	(version 20260206)
	(generator "pcbnew")
	(generator_version "10.0")
	(general
		(thickness 1.6)
		(legacy_teardrops no)
	)
	(paper "A4")
	(title_block
		(title "04192023_DAF0TMB3IC0_F0TG_MB_C_brd_V02_OCP.brd")
		(comment 1 "Grand Teton / footprints 5019-5021 of 8354")
	)
	(layers
		(0 "F.Cu" signal "TOP")
		(4 "In1.Cu" signal "GND")
		(6 "In2.Cu" signal "IN1")
		(8 "In3.Cu" signal "GND1")
		(10 "In4.Cu" signal "IN2")
		(12 "In5.Cu" signal "GND2")
		(14 "In6.Cu" signal "IN3")
		(16 "In7.Cu" signal "GND3")
		(18 "In8.Cu" signal "VCC")
		(20 "In9.Cu" signal "VCC1")
		(22 "In10.Cu" signal "GND4")
		(24 "In11.Cu" signal "IN4")
		(26 "In12.Cu" signal "GND5")
		(28 "In13.Cu" signal "IN5")
		(30 "In14.Cu" signal "GND6")
		(32 "In15.Cu" signal "IN6")
		(34 "In16.Cu" signal "GND7")
		(2 "B.Cu" signal "BOTTOM")
		(9 "F.Adhes" user "F.Adhesive")
		(11 "B.Adhes" user "B.Adhesive")
		(13 "F.Paste" user "Package Geometry/Pastemask Top")
		(15 "B.Paste" user "Package Geometry/Pastemask Bottom")
		(5 "F.SilkS" user "Ref Des/Silkscreen Top")
		(7 "B.SilkS" user "Ref Des/Silkscreen Bottom")
		(1 "F.Mask" user "Board Geometry/Soldermask Top")
		(3 "B.Mask" user "Board Geometry/Soldermask Bottom")
		(17 "Dwgs.User" user "User.Drawings")
		(19 "Cmts.User" user "User.Comments")
		(21 "Eco1.User" user "User.Eco1")
		(23 "Eco2.User" user "User.Eco2")
		(25 "Edge.Cuts" user "Board Geometry/Outline")
		(27 "Margin" user)
		(31 "F.CrtYd" user "Package Geometry/Place Bound Top")
		(29 "B.CrtYd" user "Package Geometry/Place Bound Bottom")
		(35 "F.Fab" user "Ref Des/Assembly Top")
		(33 "B.Fab" user "Ref Des/Assembly Bottom")
	)
	(footprint ""
		(layer "B.Cu")
		(at 358.58069 -391.2616 180)
		(property "Reference" "R1042"
			(at 0 0 0)
			(layer "B.SilkS")
			(hide yes)
			(effects
				(font
					(size 1.27 1.27)
				)
				(justify mirror)
			)
		)
		(property "Value" ""
			(at 0 0 0)
			(layer "B.Fab")
			(effects
				(font
					(size 1.27 1.27)
				)
				(justify mirror)
			)
		)
		(duplicate_pad_numbers_are_jumpers no)
		(fp_line
			(start 0.32512 0.175006)
			(end 0.32512 -0.175006)
			(stroke
				(width 0.1)
				(type default)
			)
			(layer "B.Fab")
		)
		(fp_line
			(start 0.32512 -0.175006)
			(end -0.32512 -0.175006)
			(stroke
				(width 0.1)
				(type default)
			)
			(layer "B.Fab")
		)
		(fp_line
			(start -0.32512 0.175006)
			(end 0.32512 0.175006)
			(stroke
				(width 0.1)
				(type default)
			)
			(layer "B.Fab")
		)
		(fp_line
			(start -0.32512 -0.175006)
			(end -0.32512 0.175006)
			(stroke
				(width 0.1)
				(type default)
			)
			(layer "B.Fab")
		)
		(pad "1" smd rect
			(at 0.2667 0)
			(size 0.3048 0.381)
			(layers "B.Cu" "B.Mask" "B.Paste")
			(net "NCF_CPU0_P1_GND")
		)
		(pad "2" smd rect
			(at -0.2667 0 180)
			(size 0.3048 0.381)
			(layers "B.Cu" "B.Mask" "B.Paste")
			(net "GND")
		)
	)
	(footprint ""
		(layer "B.Cu")
		(at 400.211798 -326.666352)
		(property "Reference" "R742"
			(at 0 0 0)
			(layer "B.SilkS")
			(hide yes)
			(effects
				(font
					(size 1.27 1.27)
				)
				(justify mirror)
			)
		)
		(property "Value" ""
			(at 0 0 0)
			(layer "B.Fab")
			(effects
				(font
					(size 1.27 1.27)
				)
				(justify mirror)
			)
		)
		(duplicate_pad_numbers_are_jumpers no)
		(fp_line
			(start -0.7874 -0.4064)
			(end -0.7874 0.4064)
			(stroke
				(width 0.1524)
				(type default)
			)
			(layer "B.SilkS")
		)
		(fp_line
			(start -0.7874 0.4064)
			(end 0.7874 0.4064)
			(stroke
				(width 0.1524)
				(type default)
			)
			(layer "B.SilkS")
		)
		(fp_line
			(start 0.7874 -0.4064)
			(end -0.7874 -0.4064)
			(stroke
				(width 0.1524)
				(type default)
			)
			(layer "B.SilkS")
		)
		(fp_line
			(start 0.7874 0.4064)
			(end 0.7874 -0.4064)
			(stroke
				(width 0.1524)
				(type default)
			)
			(layer "B.SilkS")
		)
		(fp_line
			(start -0.67945 -0.3048)
			(end -0.67945 0.3048)
			(stroke
				(width 0.1)
				(type default)
			)
			(layer "B.Fab")
		)
		(fp_line
			(start -0.67945 0.3048)
			(end -0.120396 0.3048)
			(stroke
				(width 0.1)
				(type default)
			)
			(layer "B.Fab")
		)
		(fp_line
			(start -0.12065 -0.3048)
			(end -0.67945 -0.3048)
			(stroke
				(width 0.1)
				(type default)
			)
			(layer "B.Fab")
		)
		(fp_line
			(start -0.12065 -0.2794)
			(end -0.12065 -0.3048)
			(stroke
				(width 0.1)
				(type default)
			)
			(layer "B.Fab")
		)
		(fp_line
			(start -0.120396 0.2794)
			(end 0.12065 0.2794)
			(stroke
				(width 0.1)
				(type default)
			)
			(layer "B.Fab")
		)
		(fp_line
			(start -0.120396 0.3048)
			(end -0.120396 0.2794)
			(stroke
				(width 0.1)
				(type default)
			)
			(layer "B.Fab")
		)
		(fp_line
			(start 0.12065 -0.305054)
			(end 0.12065 -0.2794)
			(stroke
				(width 0.1)
				(type default)
			)
			(layer "B.Fab")
		)
		(fp_line
			(start 0.12065 -0.2794)
			(end -0.12065 -0.2794)
			(stroke
				(width 0.1)
				(type default)
			)
			(layer "B.Fab")
		)
		(fp_line
			(start 0.12065 0.2794)
			(end 0.12065 0.3048)
			(stroke
				(width 0.1)
				(type default)
			)
			(layer "B.Fab")
		)
		(fp_line
			(start 0.12065 0.3048)
			(end 0.67945 0.3048)
			(stroke
				(width 0.1)
				(type default)
			)
			(layer "B.Fab")
		)
		(fp_line
			(start 0.67945 -0.305054)
			(end 0.12065 -0.305054)
			(stroke
				(width 0.1)
				(type default)
			)
			(layer "B.Fab")
		)
		(fp_line
			(start 0.67945 0.3048)
			(end 0.67945 -0.305054)
			(stroke
				(width 0.1)
				(type default)
			)
			(layer "B.Fab")
		)
		(pad "1" smd circle
			(at 0.40005 0 180)
			(size 0 0)
			(layers "B.Cu" "B.Mask" "B.Paste")
			(net "PVDD18_S5_P0")
		)
		(pad "2" smd circle
			(at -0.40005 0 180)
			(size 0 0)
			(layers "B.Cu" "B.Mask" "B.Paste")
			(net "PD_ESPI_CPU0_CLK2")
		)
	)
	(footprint ""
		(layer "B.Cu")
		(at 356.29596 -258.795012 180)
		(property "Reference" "C2598"
			(at 0 0 0)
			(layer "B.SilkS")
			(hide yes)
			(effects
				(font
					(size 1.27 1.27)
				)
				(justify mirror)
			)
		)
		(property "Value" ""
			(at 0 0 0)
			(layer "B.Fab")
			(effects
				(font
					(size 1.27 1.27)
				)
				(justify mirror)
			)
		)
		(duplicate_pad_numbers_are_jumpers no)
		(fp_line
			(start 0.7874 0.4064)
			(end 0.7874 -0.4064)
			(stroke
				(width 0.1524)
				(type default)
			)
			(layer "B.SilkS")
		)
		(fp_line
			(start 0.7874 -0.4064)
			(end -0.7874 -0.4064)
			(stroke
				(width 0.1524)
				(type default)
			)
			(layer "B.SilkS")
		)
		(fp_line
			(start -0.7874 0.4064)
			(end 0.7874 0.4064)
			(stroke
				(width 0.1524)
				(type default)
			)
			(layer "B.SilkS")
		)
		(fp_line
			(start -0.7874 -0.4064)
			(end -0.7874 0.4064)
			(stroke
				(width 0.1524)
				(type default)
			)
			(layer "B.SilkS")
		)
		(fp_line
			(start 0.67945 0.3048)
			(end 0.67945 -0.305054)
			(stroke
				(width 0.1)
				(type default)
			)
			(layer "B.Fab")
		)
		(fp_line
			(start 0.67945 -0.305054)
			(end 0.12065 -0.305054)
			(stroke
				(width 0.1)
				(type default)
			)
			(layer "B.Fab")
		)
		(fp_line
			(start 0.12065 0.3048)
			(end 0.67945 0.3048)
			(stroke
				(width 0.1)
				(type default)
			)
			(layer "B.Fab")
		)
		(fp_line
			(start 0.12065 0.2794)
			(end 0.12065 0.3048)
			(stroke
				(width 0.1)
				(type default)
			)
			(layer "B.Fab")
		)
		(fp_line
			(start 0.12065 -0.2794)
			(end -0.12065 -0.2794)
			(stroke
				(width 0.1)
				(type default)
			)
			(layer "B.Fab")
		)
		(fp_line
			(start 0.12065 -0.305054)
			(end 0.12065 -0.2794)
			(stroke
				(width 0.1)
				(type default)
			)
			(layer "B.Fab")
		)
		(fp_line
			(start -0.120396 0.3048)
			(end -0.120396 0.2794)
			(stroke
				(width 0.1)
				(type default)
			)
			(layer "B.Fab")
		)
		(fp_line
			(start -0.120396 0.2794)
			(end 0.12065 0.2794)
			(stroke
				(width 0.1)
				(type default)
			)
			(layer "B.Fab")
		)
		(fp_line
			(start -0.12065 -0.2794)
			(end -0.12065 -0.3048)
			(stroke
				(width 0.1)
				(type default)
			)
			(layer "B.Fab")
		)
		(fp_line
			(start -0.12065 -0.3048)
			(end -0.67945 -0.3048)
			(stroke
				(width 0.1)
				(type default)
			)
			(layer "B.Fab")
		)
		(fp_line
			(start -0.67945 0.3048)
			(end -0.120396 0.3048)
			(stroke
				(width 0.1)
				(type default)
			)
			(layer "B.Fab")
		)
		(fp_line
			(start -0.67945 -0.3048)
			(end -0.67945 0.3048)
			(stroke
				(width 0.1)
				(type default)
			)
			(layer "B.Fab")
		)
		(pad "1" smd circle
			(at 0.40005 0)
			(size 0 0)
			(layers "B.Cu" "B.Mask" "B.Paste")
			(net "PVDDIO_P0")
		)
		(pad "2" smd circle
			(at -0.40005 0)
			(size 0 0)
			(layers "B.Cu" "B.Mask" "B.Paste")
			(net "GND")
		)
	)
)
